(kicad_pcb
	(version 20260206)
	(generator "pcbnew")
	(generator_version "10.0")
	(general
		(thickness 1.6)
		(legacy_teardrops no)
	)
	(paper "A4")
	(title_block
		(title "Bryce Canyon_SCC_16316-1_OCP.brd")
		(comment 1 "Bryce Canyon / footprint 496 of 1561 (MSAS1), pads 1-38 of 38")
	)
	(layers
		(0 "F.Cu" signal "TOP")
		(4 "In1.Cu" signal "L2GND")
		(6 "In2.Cu" signal "L3")
		(8 "In3.Cu" signal "L4VCC")
		(10 "In4.Cu" signal "L5VCC")
		(12 "In5.Cu" signal "L6")
		(14 "In6.Cu" signal "L7GND")
		(2 "B.Cu" signal "BOTTOM")
		(9 "F.Adhes" user "F.Adhesive")
		(11 "B.Adhes" user "B.Adhesive")
		(13 "F.Paste" user "Package Geometry/Pastemask Top")
		(15 "B.Paste" user "Package Geometry/Pastemask Bottom")
		(5 "F.SilkS" user "Ref Des/Silkscreen Top")
		(7 "B.SilkS" user "Ref Des/Silkscreen Bottom")
		(1 "F.Mask" user "Board Geometry/Soldermask Top")
		(3 "B.Mask" user "Board Geometry/Soldermask Bottom")
		(17 "Dwgs.User" user "User.Drawings")
		(19 "Cmts.User" user "User.Comments")
		(21 "Eco1.User" user "User.Eco1")
		(23 "Eco2.User" user "User.Eco2")
		(25 "Edge.Cuts" user "Board Geometry/Outline")
		(27 "Margin" user)
		(31 "F.CrtYd" user "Package Geometry/Place Bound Top")
		(29 "B.CrtYd" user "Package Geometry/Place Bound Bottom")
		(35 "F.Fab" user "Ref Des/Assembly Top")
		(33 "B.Fab" user "Ref Des/Assembly Bottom")
	)
	(footprint ""
		(layer "F.Cu")
		(at 105.000044 -117.00002 180)
		(property "Reference" "MSAS1"
			(at 0 0 180)
			(layer "F.SilkS")
			(hide yes)
			(effects
				(font
					(size 1.27 1.27)
				)
			)
		)
		(property "Value" "MLX-CONN36-12R-1-GP-U"
			(at 19.4564 -15.1257 180)
			(unlocked yes)
			(layer "F.Fab")
			(hide yes)
			(effects
				(font
					(size 1.016 1.016)
					(thickness 0.1524)
				)
			)
		)
		(property "Device Type" "PREFIT-36P-152240-UH561"
			(at 19.4564 -16.6497 180)
			(unlocked yes)
			(layer "F.Fab")
			(hide yes)
			(effects
				(font
					(size 1.016 1.016)
					(thickness 0.1524)
				)
			)
		)
		(duplicate_pad_numbers_are_jumpers no)
		(pad "" np_thru_hole circle
			(at -5.999988 0 180)
			(size 0.254 0.254)
			(drill 2.2098)
			(layers "*.Cu" "*.Mask")
			(clearance 1.3335)
			(thermal_gap 1.3335)
		)
		(pad "" np_thru_hole circle
			(at 5.999988 0 180)
			(size 0.254 0.254)
			(drill 2.2098)
			(layers "*.Cu" "*.Mask")
			(clearance 1.3335)
			(thermal_gap 1.3335)
		)
		(pad "A1" thru_hole circle
			(at -2.999994 -2.15011 180)
			(size 0.7366 0.7366)
			(drill 0.369824)
			(layers "*.Cu" "*.Mask")
			(remove_unused_layers no)
			(net "INT_A1_CONN1")
			(clearance 0.1778)
			(thermal_gap 0.1778)
		)
		(pad "A2" thru_hole circle
			(at -2.249932 -0.750062 180)
			(size 0.7366 0.7366)
			(drill 0.369824)
			(layers "*.Cu" "*.Mask")
			(remove_unused_layers no)
			(net "INT_A2_CONN1")
			(clearance 0.1778)
			(thermal_gap 0.1778)
		)
		(pad "A3" thru_hole circle
			(at -1.500124 -1.450086 180)
			(size 0.7366 0.7366)
			(drill 0.369824)
			(layers "*.Cu" "*.Mask")
			(remove_unused_layers no)
			(net "GND")
			(clearance 0.1778)
			(thermal_gap 0.1778)
		)
		(pad "A4" thru_hole circle
			(at -0.750062 -2.15011 180)
			(size 0.7366 0.7366)
			(drill 0.369824)
			(layers "*.Cu" "*.Mask")
			(remove_unused_layers no)
			(net "PHY_CONN_TO_EXP_8_DP")
			(clearance 0.1778)
			(thermal_gap 0.1778)
		)
		(pad "A5" thru_hole circle
			(at 0 -0.750062 180)
			(size 0.7366 0.7366)
			(drill 0.369824)
			(layers "*.Cu" "*.Mask")
			(remove_unused_layers no)
			(net "PHY_CONN_TO_EXP_8_DN")
			(clearance 0.1778)
			(thermal_gap 0.1778)
		)
		(pad "A6" thru_hole circle
			(at 0.750062 -1.450086 180)
			(size 0.7366 0.7366)
			(drill 0.369824)
			(layers "*.Cu" "*.Mask")
			(remove_unused_layers no)
			(net "GND")
			(clearance 0.1778)
			(thermal_gap 0.1778)
		)
		(pad "A7" thru_hole circle
			(at 1.500124 -2.15011 180)
			(size 0.7366 0.7366)
			(drill 0.369824)
			(layers "*.Cu" "*.Mask")
			(remove_unused_layers no)
			(net "PHY_CONN_TO_EXP_9_DP")
			(clearance 0.1778)
			(thermal_gap 0.1778)
		)
		(pad "A8" thru_hole circle
			(at 2.249932 -0.750062 180)
			(size 0.7366 0.7366)
			(drill 0.369824)
			(layers "*.Cu" "*.Mask")
			(remove_unused_layers no)
			(net "PHY_CONN_TO_EXP_9_DN")
			(clearance 0.1778)
			(thermal_gap 0.1778)
		)
		(pad "A9" thru_hole circle
			(at 2.999994 -1.450086 180)
			(size 0.7366 0.7366)
			(drill 0.369824)
			(layers "*.Cu" "*.Mask")
			(remove_unused_layers no)
			(net "GND")
			(clearance 0.1778)
			(thermal_gap 0.1778)
		)
		(pad "B1" thru_hole circle
			(at -2.999994 -5.94995 180)
			(size 0.7366 0.7366)
			(drill 0.369824)
			(layers "*.Cu" "*.Mask")
			(remove_unused_layers no)
			(net "INT_B1_CONN1")
			(clearance 0.1778)
			(thermal_gap 0.1778)
		)
		(pad "B2" thru_hole circle
			(at -2.249932 -4.549902 180)
			(size 0.7366 0.7366)
			(drill 0.369824)
			(layers "*.Cu" "*.Mask")
			(remove_unused_layers no)
			(net "INT_B2_CONN1")
			(clearance 0.1778)
			(thermal_gap 0.1778)
		)
		(pad "B3" thru_hole circle
			(at -1.500124 -5.249926 180)
			(size 0.7366 0.7366)
			(drill 0.369824)
			(layers "*.Cu" "*.Mask")
			(remove_unused_layers no)
			(net "GND")
			(clearance 0.1778)
			(thermal_gap 0.1778)
		)
		(pad "B4" thru_hole circle
			(at -0.750062 -5.94995 180)
			(size 0.7366 0.7366)
			(drill 0.369824)
			(layers "*.Cu" "*.Mask")
			(remove_unused_layers no)
			(net "PHY_CONN_TO_EXP_10_DP")
			(clearance 0.1778)
			(thermal_gap 0.1778)
		)
		(pad "B5" thru_hole circle
			(at 0 -4.549902 180)
			(size 0.7366 0.7366)
			(drill 0.369824)
			(layers "*.Cu" "*.Mask")
			(remove_unused_layers no)
			(net "PHY_CONN_TO_EXP_10_DN")
			(clearance 0.1778)
			(thermal_gap 0.1778)
		)
		(pad "B6" thru_hole circle
			(at 0.750062 -5.249926 180)
			(size 0.7366 0.7366)
			(drill 0.369824)
			(layers "*.Cu" "*.Mask")
			(remove_unused_layers no)
			(net "GND")
			(clearance 0.1778)
			(thermal_gap 0.1778)
		)
		(pad "B7" thru_hole circle
			(at 1.500124 -5.94995 180)
			(size 0.7366 0.7366)
			(drill 0.369824)
			(layers "*.Cu" "*.Mask")
			(remove_unused_layers no)
			(net "PHY_CONN_TO_EXP_11_DP")
			(clearance 0.1778)
			(thermal_gap 0.1778)
		)
		(pad "B8" thru_hole circle
			(at 2.249932 -4.549902 180)
			(size 0.7366 0.7366)
			(drill 0.369824)
			(layers "*.Cu" "*.Mask")
			(remove_unused_layers no)
			(net "PHY_CONN_TO_EXP_11_DN")
			(clearance 0.1778)
			(thermal_gap 0.1778)
		)
		(pad "B9" thru_hole circle
			(at 2.999994 -5.249926 180)
			(size 0.7366 0.7366)
			(drill 0.369824)
			(layers "*.Cu" "*.Mask")
			(remove_unused_layers no)
			(net "GND")
			(clearance 0.1778)
			(thermal_gap 0.1778)
		)
		(pad "C1" thru_hole circle
			(at -2.999994 -9.750044 180)
			(size 0.7366 0.7366)
			(drill 0.369824)
			(layers "*.Cu" "*.Mask")
			(remove_unused_layers no)
			(net "INT_C1_CONN1")
			(clearance 0.1778)
			(thermal_gap 0.1778)
		)
		(pad "C2" thru_hole circle
			(at -2.249932 -8.349996 180)
			(size 0.7366 0.7366)
			(drill 0.369824)
			(layers "*.Cu" "*.Mask")
			(remove_unused_layers no)
			(net "INT_C2_CONN1")
			(clearance 0.1778)
			(thermal_gap 0.1778)
		)
		(pad "C3" thru_hole circle
			(at -1.500124 -9.05002 180)
			(size 0.7366 0.7366)
			(drill 0.369824)
			(layers "*.Cu" "*.Mask")
			(remove_unused_layers no)
			(net "GND")
			(clearance 0.1778)
			(thermal_gap 0.1778)
		)
		(pad "C4" thru_hole circle
			(at -0.750062 -9.750044 180)
			(size 0.7366 0.7366)
			(drill 0.369824)
			(layers "*.Cu" "*.Mask")
			(remove_unused_layers no)
			(net "PHY_EXP_TO_CONN_8_DP")
			(clearance 0.1778)
			(thermal_gap 0.1778)
		)
		(pad "C5" thru_hole circle
			(at 0 -8.349996 180)
			(size 0.7366 0.7366)
			(drill 0.369824)
			(layers "*.Cu" "*.Mask")
			(remove_unused_layers no)
			(net "PHY_EXP_TO_CONN_8_DN")
			(clearance 0.1778)
			(thermal_gap 0.1778)
		)
		(pad "C6" thru_hole circle
			(at 0.750062 -9.05002 180)
			(size 0.7366 0.7366)
			(drill 0.369824)
			(layers "*.Cu" "*.Mask")
			(remove_unused_layers no)
			(net "GND")
			(clearance 0.1778)
			(thermal_gap 0.1778)
		)
		(pad "C7" thru_hole circle
			(at 1.500124 -9.750044 180)
			(size 0.7366 0.7366)
			(drill 0.369824)
			(layers "*.Cu" "*.Mask")
			(remove_unused_layers no)
			(net "PHY_EXP_TO_CONN_9_DP")
			(clearance 0.1778)
			(thermal_gap 0.1778)
		)
		(pad "C8" thru_hole circle
			(at 2.249932 -8.349996 180)
			(size 0.7366 0.7366)
			(drill 0.369824)
			(layers "*.Cu" "*.Mask")
			(remove_unused_layers no)
			(net "PHY_EXP_TO_CONN_9_DN")
			(clearance 0.1778)
			(thermal_gap 0.1778)
		)
		(pad "C9" thru_hole circle
			(at 2.999994 -9.05002 180)
			(size 0.7366 0.7366)
			(drill 0.369824)
			(layers "*.Cu" "*.Mask")
			(remove_unused_layers no)
			(net "GND")
			(clearance 0.1778)
			(thermal_gap 0.1778)
		)
		(pad "D1" thru_hole circle
			(at -2.999994 -13.549884 180)
			(size 0.7366 0.7366)
			(drill 0.369824)
			(layers "*.Cu" "*.Mask")
			(remove_unused_layers no)
			(net "INT_D1_CONN1")
			(clearance 0.1778)
			(thermal_gap 0.1778)
		)
		(pad "D2" thru_hole circle
			(at -2.249932 -12.15009 180)
			(size 0.7366 0.7366)
			(drill 0.369824)
			(layers "*.Cu" "*.Mask")
			(remove_unused_layers no)
			(net "INT_D2_CONN1")
			(clearance 0.1778)
			(thermal_gap 0.1778)
		)
		(pad "D3" thru_hole circle
			(at -1.500124 -12.850114 180)
			(size 0.7366 0.7366)
			(drill 0.369824)
			(layers "*.Cu" "*.Mask")
			(remove_unused_layers no)
			(net "GND")
			(clearance 0.1778)
			(thermal_gap 0.1778)
		)
		(pad "D4" thru_hole circle
			(at -0.750062 -13.549884 180)
			(size 0.7366 0.7366)
			(drill 0.369824)
			(layers "*.Cu" "*.Mask")
			(remove_unused_layers no)
			(net "PHY_EXP_TO_CONN_10_DP")
			(clearance 0.1778)
			(thermal_gap 0.1778)
		)
		(pad "D5" thru_hole circle
			(at 0 -12.15009 180)
			(size 0.7366 0.7366)
			(drill 0.369824)
			(layers "*.Cu" "*.Mask")
			(remove_unused_layers no)
			(net "PHY_EXP_TO_CONN_10_DN")
			(clearance 0.1778)
			(thermal_gap 0.1778)
		)
		(pad "D6" thru_hole circle
			(at 0.750062 -12.850114 180)
			(size 0.7366 0.7366)
			(drill 0.369824)
			(layers "*.Cu" "*.Mask")
			(remove_unused_layers no)
			(net "GND")
			(clearance 0.1778)
			(thermal_gap 0.1778)
		)
		(pad "D7" thru_hole circle
			(at 1.500124 -13.549884 180)
			(size 0.7366 0.7366)
			(drill 0.369824)
			(layers "*.Cu" "*.Mask")
			(remove_unused_layers no)
			(net "PHY_EXP_TO_CONN_11_DP")
			(clearance 0.1778)
			(thermal_gap 0.1778)
		)
		(pad "D8" thru_hole circle
			(at 2.249932 -12.15009 180)
			(size 0.7366 0.7366)
			(drill 0.369824)
			(layers "*.Cu" "*.Mask")
			(remove_unused_layers no)
			(net "PHY_EXP_TO_CONN_11_DN")
			(clearance 0.1778)
			(thermal_gap 0.1778)
		)
		(pad "D9" thru_hole circle
			(at 2.999994 -12.850114 180)
			(size 0.7366 0.7366)
			(drill 0.369824)
			(layers "*.Cu" "*.Mask")
			(remove_unused_layers no)
			(net "GND")
			(clearance 0.1778)
			(thermal_gap 0.1778)
		)
	)
)
